# SCM (Grand Teton) — schematic netlist excerpt (pin names and nets, part order shuffled) for the footprints in the layout excerpt that follows; sources: Cadence DE-HDL packaged netlist, KiCad conversion of 12092022_DA0F0TMDCD0_F0T_Management_Board_D_brd_V3_OCP.brd

R840  Q_RES  33.2 1% CHIP  pkg 0402LF  page 13 : A = PWRGD_SYS_PWROK ; B = PWRGD_SYS_PWROK_BMC
R494  Q_RES  33.2 1% CHIP  pkg 0402LF  page 13 : A = RST_BMC_SELF_HW_R1 ; B = RST_BMC_SELF_HW

(kicad_pcb
	(version 20260206)
	(generator "pcbnew")
	(generator_version "10.0")
	(general
		(thickness 1.6)
		(legacy_teardrops no)
	)
	(paper "A4")
	(title_block
		(title "12092022_DA0F0TMDCD0_F0T_Management_Board_D_brd_V3_OCP.brd")
		(comment 1 "Grand Teton / footprints 643-644 of 1440")
	)
	(layers
		(0 "F.Cu" signal "TOP")
		(4 "In1.Cu" signal "GND")
		(6 "In2.Cu" signal "IN1")
		(8 "In3.Cu" signal "GND1")
		(10 "In4.Cu" signal "IN2")
		(12 "In5.Cu" signal "VCC")
		(14 "In6.Cu" signal "VCC1")
		(16 "In7.Cu" signal "IN3")
		(18 "In8.Cu" signal "GND2")
		(20 "In9.Cu" signal "IN4")
		(22 "In10.Cu" signal "GND3")
		(2 "B.Cu" signal "BOTTOM")
		(9 "F.Adhes" user "F.Adhesive")
		(11 "B.Adhes" user "B.Adhesive")
		(13 "F.Paste" user "Package Geometry/Pastemask Top")
		(15 "B.Paste" user "Package Geometry/Pastemask Bottom")
		(5 "F.SilkS" user "Ref Des/Silkscreen Top")
		(7 "B.SilkS" user "Ref Des/Silkscreen Bottom")
		(1 "F.Mask" user "Board Geometry/Soldermask Top")
		(3 "B.Mask" user "Board Geometry/Soldermask Bottom")
		(17 "Dwgs.User" user "User.Drawings")
		(19 "Cmts.User" user "User.Comments")
		(21 "Eco1.User" user "User.Eco1")
		(23 "Eco2.User" user "User.Eco2")
		(25 "Edge.Cuts" user "Board Geometry/Outline")
		(27 "Margin" user)
		(31 "F.CrtYd" user "Package Geometry/Place Bound Top")
		(29 "B.CrtYd" user "Package Geometry/Place Bound Bottom")
		(35 "F.Fab" user "Ref Des/Assembly Top")
		(33 "B.Fab" user "Ref Des/Assembly Bottom")
	)
	(footprint ""
		(layer "F.Cu")
		(at 56.3372 -63.6524 90)
		(property "Reference" "R494"
			(at 0 0 90)
			(layer "F.SilkS")
			(hide yes)
			(effects
				(font
					(size 1.27 1.27)
				)
			)
		)
		(property "Value" ""
			(at 0 0 90)
			(layer "F.Fab")
			(effects
				(font
					(size 1.27 1.27)
				)
			)
		)
		(duplicate_pad_numbers_are_jumpers no)
		(fp_line
			(start 0.7874 -0.4064)
			(end 0.7874 0.4064)
			(stroke
				(width 0.1524)
				(type default)
			)
			(layer "F.SilkS")
		)
		(fp_line
			(start -0.7874 -0.4064)
			(end 0.7874 -0.4064)
			(stroke
				(width 0.1524)
				(type default)
			)
			(layer "F.SilkS")
		)
		(fp_line
			(start 0.7874 0.4064)
			(end -0.7874 0.4064)
			(stroke
				(width 0.1524)
				(type default)
			)
			(layer "F.SilkS")
		)
		(fp_line
			(start -0.7874 0.4064)
			(end -0.7874 -0.4064)
			(stroke
				(width 0.1524)
				(type default)
			)
			(layer "F.SilkS")
		)
		(fp_line
			(start -0.12065 -0.305054)
			(end -0.12065 -0.2794)
			(stroke
				(width 0.1)
				(type default)
			)
			(layer "F.Fab")
		)
		(fp_line
			(start -0.67945 -0.305054)
			(end -0.12065 -0.305054)
			(stroke
				(width 0.1)
				(type default)
			)
			(layer "F.Fab")
		)
		(fp_line
			(start 0.67945 -0.3048)
			(end 0.67945 0.3048)
			(stroke
				(width 0.1)
				(type default)
			)
			(layer "F.Fab")
		)
		(fp_line
			(start 0.12065 -0.3048)
			(end 0.67945 -0.3048)
			(stroke
				(width 0.1)
				(type default)
			)
			(layer "F.Fab")
		)
		(fp_line
			(start 0.12065 -0.2794)
			(end 0.12065 -0.3048)
			(stroke
				(width 0.1)
				(type default)
			)
			(layer "F.Fab")
		)
		(fp_line
			(start -0.12065 -0.2794)
			(end 0.12065 -0.2794)
			(stroke
				(width 0.1)
				(type default)
			)
			(layer "F.Fab")
		)
		(fp_line
			(start 0.120396 0.2794)
			(end -0.12065 0.2794)
			(stroke
				(width 0.1)
				(type default)
			)
			(layer "F.Fab")
		)
		(fp_line
			(start -0.12065 0.2794)
			(end -0.12065 0.3048)
			(stroke
				(width 0.1)
				(type default)
			)
			(layer "F.Fab")
		)
		(fp_line
			(start 0.67945 0.3048)
			(end 0.120396 0.3048)
			(stroke
				(width 0.1)
				(type default)
			)
			(layer "F.Fab")
		)
		(fp_line
			(start 0.120396 0.3048)
			(end 0.120396 0.2794)
			(stroke
				(width 0.1)
				(type default)
			)
			(layer "F.Fab")
		)
		(fp_line
			(start -0.12065 0.3048)
			(end -0.67945 0.3048)
			(stroke
				(width 0.1)
				(type default)
			)
			(layer "F.Fab")
		)
		(fp_line
			(start -0.67945 0.3048)
			(end -0.67945 -0.305054)
			(stroke
				(width 0.1)
				(type default)
			)
			(layer "F.Fab")
		)
		(pad "1" smd circle
			(at -0.40005 0 90)
			(size 0 0)
			(layers "F.Cu" "F.Mask" "F.Paste")
			(net "RST_BMC_SELF_HW_R1")
		)
		(pad "2" smd circle
			(at 0.40005 0 90)
			(size 0 0)
			(layers "F.Cu" "F.Mask" "F.Paste")
			(net "RST_BMC_SELF_HW")
		)
	)
	(footprint ""
		(layer "F.Cu")
		(at 56.7182 -30.861 90)
		(property "Reference" "R840"
			(at 0 0 90)
			(layer "F.SilkS")
			(hide yes)
			(effects
				(font
					(size 1.27 1.27)
				)
			)
		)
		(property "Value" ""
			(at 0 0 90)
			(layer "F.Fab")
			(effects
				(font
					(size 1.27 1.27)
				)
			)
		)
		(duplicate_pad_numbers_are_jumpers no)
		(fp_line
			(start 0.7874 -0.4064)
			(end 0.7874 0.4064)
			(stroke
				(width 0.1524)
				(type default)
			)
			(layer "F.SilkS")
		)
		(fp_line
			(start -0.7874 -0.4064)
			(end 0.7874 -0.4064)
			(stroke
				(width 0.1524)
				(type default)
			)
			(layer "F.SilkS")
		)
		(fp_line
			(start 0.7874 0.4064)
			(end -0.7874 0.4064)
			(stroke
				(width 0.1524)
				(type default)
			)
			(layer "F.SilkS")
		)
		(fp_line
			(start -0.7874 0.4064)
			(end -0.7874 -0.4064)
			(stroke
				(width 0.1524)
				(type default)
			)
			(layer "F.SilkS")
		)
		(fp_line
			(start -0.12065 -0.305054)
			(end -0.12065 -0.2794)
			(stroke
				(width 0.1)
				(type default)
			)
			(layer "F.Fab")
		)
		(fp_line
			(start -0.67945 -0.305054)
			(end -0.12065 -0.305054)
			(stroke
				(width 0.1)
				(type default)
			)
			(layer "F.Fab")
		)
		(fp_line
			(start 0.67945 -0.3048)
			(end 0.67945 0.3048)
			(stroke
				(width 0.1)
				(type default)
			)
			(layer "F.Fab")
		)
		(fp_line
			(start 0.12065 -0.3048)
			(end 0.67945 -0.3048)
			(stroke
				(width 0.1)
				(type default)
			)
			(layer "F.Fab")
		)
		(fp_line
			(start 0.12065 -0.2794)
			(end 0.12065 -0.3048)
			(stroke
				(width 0.1)
				(type default)
			)
			(layer "F.Fab")
		)
		(fp_line
			(start -0.12065 -0.2794)
			(end 0.12065 -0.2794)
			(stroke
				(width 0.1)
				(type default)
			)
			(layer "F.Fab")
		)
		(fp_line
			(start 0.120396 0.2794)
			(end -0.12065 0.2794)
			(stroke
				(width 0.1)
				(type default)
			)
			(layer "F.Fab")
		)
		(fp_line
			(start -0.12065 0.2794)
			(end -0.12065 0.3048)
			(stroke
				(width 0.1)
				(type default)
			)
			(layer "F.Fab")
		)
		(fp_line
			(start 0.67945 0.3048)
			(end 0.120396 0.3048)
			(stroke
				(width 0.1)
				(type default)
			)
			(layer "F.Fab")
		)
		(fp_line
			(start 0.120396 0.3048)
			(end 0.120396 0.2794)
			(stroke
				(width 0.1)
				(type default)
			)
			(layer "F.Fab")
		)
		(fp_line
			(start -0.12065 0.3048)
			(end -0.67945 0.3048)
			(stroke
				(width 0.1)
				(type default)
			)
			(layer "F.Fab")
		)
		(fp_line
			(start -0.67945 0.3048)
			(end -0.67945 -0.305054)
			(stroke
				(width 0.1)
				(type default)
			)
			(layer "F.Fab")
		)
		(pad "1" smd circle
			(at -0.40005 0 90)
			(size 0 0)
			(layers "F.Cu" "F.Mask" "F.Paste")
			(net "PWRGD_SYS_PWROK")
		)
		(pad "2" smd circle
			(at 0.40005 0 90)
			(size 0 0)
			(layers "F.Cu" "F.Mask" "F.Paste")
			(net "PWRGD_SYS_PWROK_BMC")
		)
	)
)
